(kicad_pcb
	(version 20221018)
	(generator pcbnew)
	(general
    (thickness 1.518)
  )
	(paper "A4")
	(title_block
    (title "Kria K26 Devboard")
    (date "2024-03-26")
    (rev "1.2.5")
    (comment 1 "www.antmicro.com")
    (comment 2 "Antmicro Ltd.")
		(comment 9 "footprints 209-217 of 660")
	)
	(layers
    (0 "F.Cu" mixed)
    (1 "In1.Cu" power)
    (2 "In2.Cu" mixed)
    (3 "In3.Cu" power)
    (4 "In4.Cu" mixed)
    (5 "In5.Cu" power)
    (6 "In6.Cu" mixed)
    (31 "B.Cu" power)
    (32 "B.Adhes" user "B.Adhesive")
    (33 "F.Adhes" user "F.Adhesive")
    (34 "B.Paste" user)
    (35 "F.Paste" user)
    (36 "B.SilkS" user "B.Silkscreen")
    (37 "F.SilkS" user "F.Silkscreen")
    (38 "B.Mask" user)
    (39 "F.Mask" user)
    (40 "Dwgs.User" user "User.Drawings")
    (41 "Cmts.User" user "User.Comments")
    (42 "Eco1.User" user "User.Eco1")
    (43 "Eco2.User" user "User.Eco2")
    (44 "Edge.Cuts" user)
    (45 "Margin" user)
    (46 "B.CrtYd" user "B.Courtyard")
    (47 "F.CrtYd" user "F.Courtyard")
    (48 "B.Fab" user)
    (49 "F.Fab" user)
  )
	(footprint "kria-k26-devboard-footprints:D_SOD-323F" (layer "F.Cu")
    (at 186.6 69.15)
    (property "Author" "Antmicro")
    (property "License" "Apache-2.0")
    (property "MPN" "1N4148WS")
    (property "Manufacturer" "ON Semiconductor")
    (property "Sheetfile" "supply-oring.kicad_sch")
    (property "Sheetname" "Supply ORing")
    (property "ki_description" "Small Signal Fast Switching Diode")
    (attr smd)
    (fp_text reference "D21" (at -0.92 1.67) (layer "F.SilkS")
        (effects (font (size 0.7 0.7) (thickness 0.15)) (justify left bottom))
    )
    (fp_text value "1N4148WS" (at -1.7 1.9) (layer "F.Fab") hide
        (effects (font (size 0.7 0.7) (thickness 0.15)) (justify left bottom))
    )
    (fp_text user "${REFERENCE}" (at -1.8 3.2) (layer "F.Fab") hide
        (effects (font (size 0.7 0.7) (thickness 0.15)) (justify left bottom))
    )
    (fp_text user "Author: Antmicro" (at -1.8 4.46) (layer "F.Fab") hide
        (effects (font (size 0.7 0.7) (thickness 0.15)) (justify left bottom))
    )
    (fp_text user "License: Apache-2.0" (at -1.8 5.8) (layer "F.Fab") hide
        (effects (font (size 0.7 0.7) (thickness 0.15)) (justify left bottom))
    )
    (fp_line (start -0.975 -0.75) (end -0.975 -0.45)
      (stroke (width 0.15) (type solid)) (layer "F.SilkS"))
    (fp_line (start -0.975 0.748) (end -0.975 0.45)
      (stroke (width 0.15) (type solid)) (layer "F.SilkS"))
    (fp_line (start -0.625 -0.75) (end -0.975 -0.75)
      (stroke (width 0.15) (type solid)) (layer "F.SilkS"))
    (fp_line (start -0.625 0.748) (end -0.975 0.748)
      (stroke (width 0.15) (type solid)) (layer "F.SilkS"))
    (fp_line (start -0.5 -0.426) (end -0.5 0.424)
      (stroke (width 0.15) (type solid)) (layer "F.SilkS"))
    (fp_line (start 0.623 -0.75) (end 0.973 -0.75)
      (stroke (width 0.15) (type solid)) (layer "F.SilkS"))
    (fp_line (start 0.973 -0.75) (end 0.973 -0.45)
      (stroke (width 0.15) (type solid)) (layer "F.SilkS"))
    (fp_line (start 0.973 0.45) (end 0.973 0.748)
      (stroke (width 0.15) (type solid)) (layer "F.SilkS"))
    (fp_line (start 0.973 0.748) (end 0.623 0.748)
      (stroke (width 0.15) (type solid)) (layer "F.SilkS"))
    (fp_rect (start -1.6 -0.827) (end 1.599 0.825)
      (stroke (width 0.05) (type solid)) (fill none) (layer "F.CrtYd"))
    (fp_line (start -0.85 -0.625) (end 0.848 -0.625)
      (stroke (width 0.15) (type solid)) (layer "F.Fab"))
    (fp_line (start -0.85 0.623) (end -0.85 -0.625)
      (stroke (width 0.15) (type solid)) (layer "F.Fab"))
    (fp_line (start -0.85 0.623) (end 0.848 0.623)
      (stroke (width 0.15) (type solid)) (layer "F.Fab"))
    (fp_line (start 0.848 -0.625) (end 0.848 0.623)
      (stroke (width 0.15) (type solid)) (layer "F.Fab"))
    (pad "A" smd roundrect (at 1.05 0) (size 0.8 0.6) (layers "F.Cu" "F.Paste" "F.Mask") (roundrect_rratio 0.15)
      (net 331 "Net-(U58-GND)") (pinfunction "A") (pintype "passive"))
    (pad "K" smd roundrect (at -1.051 0) (size 0.8 0.6) (layers "F.Cu" "F.Paste" "F.Mask") (roundrect_rratio 0.15)
      (net 22 "/Power Supply/DC Input/DC_IN") (pinfunction "K") (pintype "passive"))
  )
	(footprint "kria-k26-devboard-footprints:TP_SMD_0.75mm" (layer "F.Cu")
    (at 118.6 92.35)
    (property "Author" "Antmicro")
    (property "License" "Apache-2.0")
    (property "MPN" "")
    (property "Manufacturer" "")
    (property "Sheetfile" "usb.kicad_sch")
    (property "Sheetname" "USB")
    (property "ki_description" "Test Point 0.75mm")
    (attr exclude_from_pos_files)
    (fp_text reference "TP10" (at -0.5 1.54 90) (layer "F.SilkS")
        (effects (font (size 0.7 0.7) (thickness 0.15)) (justify left bottom))
    )
    (fp_text value "TP_0.75mm_SMD" (at 0 1.2) (layer "F.Fab") hide
        (effects (font (size 0.7 0.7) (thickness 0.15)) (justify left bottom))
    )
    (fp_text user "Author: Antmicro" (at -0.4 3.901) (layer "F.Fab") hide
        (effects (font (size 0.7 0.7) (thickness 0.15)) (justify left bottom))
    )
    (fp_text user "License: Apache-2.0" (at -0.4 5.101) (layer "F.Fab") hide
        (effects (font (size 0.7 0.7) (thickness 0.15)) (justify left bottom))
    )
    (fp_text user "${REFERENCE}" (at -0.4 2.7) (layer "F.Fab") hide
        (effects (font (size 0.7 0.7) (thickness 0.15)) (justify left bottom))
    )
    (pad "1" smd circle (at 0 0) (size 0.75 0.75) (layers "F.Cu" "F.Mask")
      (net 275 "/USB/VBUS") (pinfunction "1") (pintype "passive"))
  )
	(footprint "kria-k26-devboard-footprints:TP_SMD_0.75mm" (layer "F.Cu")
    (at 106.11 147.11)
    (property "Author" "Antmicro")
    (property "License" "Apache-2.0")
    (property "MPN" "")
    (property "Manufacturer" "")
    (property "Sheetfile" "reset.kicad_sch")
    (property "Sheetname" "Reset logic")
    (property "ki_description" "Test Point 0.75mm")
    (attr exclude_from_pos_files)
    (fp_text reference "TP13" (at -0.51 -0.5) (layer "F.SilkS")
        (effects (font (size 0.7 0.7) (thickness 0.15)) (justify left bottom))
    )
    (fp_text value "TP_0.75mm_SMD" (at 0 1.2) (layer "F.Fab") hide
        (effects (font (size 0.7 0.7) (thickness 0.15)) (justify left bottom))
    )
    (fp_text user "License: Apache-2.0" (at -0.4 5.101) (layer "F.Fab") hide
        (effects (font (size 0.7 0.7) (thickness 0.15)) (justify left bottom))
    )
    (fp_text user "Author: Antmicro" (at -0.4 3.901) (layer "F.Fab") hide
        (effects (font (size 0.7 0.7) (thickness 0.15)) (justify left bottom))
    )
    (fp_text user "${REFERENCE}" (at -0.4 2.7) (layer "F.Fab") hide
        (effects (font (size 0.7 0.7) (thickness 0.15)) (justify left bottom))
    )
    (pad "1" smd circle (at 0 0) (size 0.75 0.75) (layers "F.Cu" "F.Mask")
      (net 151 "/Debug and JTAG/~{PS_POR}") (pinfunction "1") (pintype "passive"))
  )
	(footprint "kria-k26-devboard-footprints:C_0402_1005Metric" (layer "F.Cu")
    (at 125.55 92.91 90)
    (descr "Capacitor SMD 0402")
    (tags "capacitor SMD 0402")
    (property "Author" "Antmicro")
    (property "Dielectric" "X5R")
    (property "License" "Apache-2.0")
    (property "MPN" "GRM155R61H104KE14D")
    (property "Manufacturer" "Murata")
    (property "Sheetfile" "usb.kicad_sch")
    (property "Sheetname" "USB")
    (property "Val" "100n")
    (property "Voltage" "50V")
    (property "ki_description" " ")
    (attr smd)
    (fp_text reference "C55" (at -1.94 -3.25 90) (layer "F.SilkS")
        (effects (font (size 0.7 0.7) (thickness 0.15)) (justify left bottom))
    )
    (fp_text value "C_100n_0402" (at 0 1.4 90) (layer "F.Fab") hide
        (effects (font (size 0.7 0.7) (thickness 0.15)) (justify left bottom))
    )
    (fp_text user "Author: Antmicro" (at -0.932 4.17 90) (layer "F.Fab") hide
        (effects (font (size 0.7 0.7) (thickness 0.15)) (justify left bottom))
    )
    (fp_text user "${REFERENCE}" (at -0.932 3.168 90) (layer "F.Fab") hide
        (effects (font (size 0.7 0.7) (thickness 0.15)) (justify left bottom))
    )
    (fp_text user "License: Apache-2.0" (at -0.932 5.17 90) (layer "F.Fab") hide
        (effects (font (size 0.7 0.7) (thickness 0.15)) (justify left bottom))
    )
    (fp_rect (start -0.94 -0.47) (end 0.94 0.47)
      (stroke (width 0.05) (type solid)) (fill none) (layer "F.CrtYd"))
    (fp_rect (start -0.499 -0.249) (end 0.499 0.249)
      (stroke (width 0.15) (type solid)) (fill none) (layer "F.Fab"))
    (pad "1" smd roundrect (at -0.484 0 90) (size 0.59 0.64) (layers "F.Cu" "F.Paste" "F.Mask") (roundrect_rratio 0.25)
      (net 59 "/USB/GTR_DP2_M2C_N") (pintype "passive"))
    (pad "2" smd roundrect (at 0.484 0 90) (size 0.59 0.64) (layers "F.Cu" "F.Paste" "F.Mask") (roundrect_rratio 0.25)
      (net 321 "/USB/GTR_DP2_M2C_C_N") (pintype "passive"))
  )
	(footprint "kria-k26-devboard-footprints:C_0402_1005Metric" (layer "F.Cu")
    (at 124.6 92.91 90)
    (descr "Capacitor SMD 0402")
    (tags "capacitor SMD 0402")
    (property "Author" "Antmicro")
    (property "Dielectric" "X5R")
    (property "License" "Apache-2.0")
    (property "MPN" "GRM155R61H104KE14D")
    (property "Manufacturer" "Murata")
    (property "Sheetfile" "usb.kicad_sch")
    (property "Sheetname" "USB")
    (property "Val" "100n")
    (property "Voltage" "50V")
    (property "ki_description" " ")
    (attr smd)
    (fp_text reference "C54" (at -1.94 -3.25 90) (layer "F.SilkS")
        (effects (font (size 0.7 0.7) (thickness 0.15)) (justify left bottom))
    )
    (fp_text value "C_100n_0402" (at 0 1.4 90) (layer "F.Fab") hide
        (effects (font (size 0.7 0.7) (thickness 0.15)) (justify left bottom))
    )
    (fp_text user "License: Apache-2.0" (at -0.932 5.17 90) (layer "F.Fab") hide
        (effects (font (size 0.7 0.7) (thickness 0.15)) (justify left bottom))
    )
    (fp_text user "Author: Antmicro" (at -0.932 4.17 90) (layer "F.Fab") hide
        (effects (font (size 0.7 0.7) (thickness 0.15)) (justify left bottom))
    )
    (fp_text user "${REFERENCE}" (at -0.932 3.168 90) (layer "F.Fab") hide
        (effects (font (size 0.7 0.7) (thickness 0.15)) (justify left bottom))
    )
    (fp_rect (start -0.94 -0.47) (end 0.94 0.47)
      (stroke (width 0.05) (type solid)) (fill none) (layer "F.CrtYd"))
    (fp_rect (start -0.499 -0.249) (end 0.499 0.249)
      (stroke (width 0.15) (type solid)) (fill none) (layer "F.Fab"))
    (pad "1" smd roundrect (at -0.484 0 90) (size 0.59 0.64) (layers "F.Cu" "F.Paste" "F.Mask") (roundrect_rratio 0.25)
      (net 58 "/USB/GTR_DP2_M2C_P") (pintype "passive"))
    (pad "2" smd roundrect (at 0.484 0 90) (size 0.59 0.64) (layers "F.Cu" "F.Paste" "F.Mask") (roundrect_rratio 0.25)
      (net 320 "/USB/GTR_DP2_M2C_C_P") (pintype "passive"))
  )
	(footprint "kria-k26-devboard-footprints:XDFN4" (layer "F.Cu")
    (at 83.875 118.050001)
    (property "Author" "Antmicro")
    (property "License" "Apache-2.0")
    (property "MPN" "AP7340-18FS4-7")
    (property "Manufacturer" "Diodes Incorporated")
    (property "Sheetfile" "camera.kicad_sch")
    (property "Sheetname" "Camera interface")
    (property "dnp" "")
    (property "ki_description" "Linear voltage regulator")
    (property "ki_keywords" "SMT, PMIC, IC, VOLTAGE, LDO")
    (attr exclude_from_pos_files)
    (fp_text reference "U11" (at -1.055 -2.720001) (layer "F.SilkS")
        (effects (font (size 0.7 0.7) (thickness 0.15)) (justify left bottom))
    )
    (fp_text value "AP7340-18FS4-7" (at -1.73 1.92) (layer "F.Fab") hide
        (effects (font (size 0.7 0.7) (thickness 0.15)) (justify left bottom))
    )
    (fp_text user "${REFERENCE}" (at -1.73 6.32) (layer "F.Fab") hide
        (effects (font (size 0.7 0.7) (thickness 0.15)) (justify left bottom))
    )
    (fp_text user "License: Apache-2.0" (at -1.73 5.12) (layer "F.Fab") hide
        (effects (font (size 0.7 0.7) (thickness 0.15)) (justify left bottom))
    )
    (fp_text user "Author: Antmicro" (at -1.73 3.92) (layer "F.Fab") hide
        (effects (font (size 0.7 0.7) (thickness 0.15)) (justify left bottom))
    )
    (fp_poly
      (pts
        (xy -0.652 -0.452)
        (xy -0.18 -0.452)
        (xy -0.43 -0.202)
        (xy -0.652 -0.202)
      )

      (stroke (width 0.01) (type solid)) (fill solid) (layer "F.Paste"))
    (fp_poly
      (pts
        (xy -0.152 -0.152)
        (xy 0.15 -0.152)
        (xy 0.15 0.15)
        (xy -0.152 0.15)
      )

      (stroke (width 0.01) (type solid)) (fill solid) (layer "F.Paste"))
    (fp_poly
      (pts
        (xy -0.652 0.45)
        (xy -0.25 0.45)
        (xy -0.25 0.378)
        (xy -0.43 0.2)
        (xy -0.652 0.2)
      )

      (stroke (width 0.01) (type solid)) (fill solid) (layer "F.Paste"))
    (fp_poly
      (pts
        (xy 0.65 -0.452)
        (xy 0.248 -0.452)
        (xy 0.248 -0.38)
        (xy 0.428 -0.202)
        (xy 0.65 -0.202)
      )

      (stroke (width 0.01) (type solid)) (fill solid) (layer "F.Paste"))
    (fp_poly
      (pts
        (xy 0.65 0.45)
        (xy 0.248 0.45)
        (xy 0.248 0.378)
        (xy 0.428 0.2)
        (xy 0.65 0.2)
      )

      (stroke (width 0.01) (type solid)) (fill solid) (layer "F.Paste"))
    (fp_circle (center -0.75 -0.6) (end -0.699 -0.6)
      (stroke (width 0.15) (type solid)) (fill solid) (layer "F.SilkS"))
    (fp_rect (start -0.8 -0.8) (end 0.8 0.8)
      (stroke (width 0.05) (type solid)) (fill none) (layer "F.CrtYd"))
    (fp_line (start -0.5 -0.3) (end -0.3 -0.5)
      (stroke (width 0.15) (type solid)) (layer "F.Fab"))
    (fp_rect (start -0.5 -0.5) (end 0.498 0.498)
      (stroke (width 0.15) (type solid)) (fill none) (layer "F.Fab"))
    (pad "1" smd custom (at -0.452 -0.327) (size 0.1 0.1) (layers "F.Cu")
      (net 322 "PL_1V8") (pinfunction "VOUT") (pintype "power_out") (zone_connect 2)
      (options (clearance outline) (anchor rect))
      (primitives
        (gr_poly
          (pts
            (xy -0.2 -0.125)
            (xy 0.27 -0.125)
            (xy 0.02 0.125)
            (xy -0.2 0.125)
          )
          (width 0.01) (fill yes))
      ))
    (pad "2" smd custom (at -0.452 0.325) (size 0.1 0.1) (layers "F.Cu")
      (net 1 "GND") (pinfunction "GND") (pintype "power_in") (zone_connect 2)
      (options (clearance outline) (anchor rect))
      (primitives
        (gr_poly
          (pts
            (xy -0.2 0.125)
            (xy 0.2 0.125)
            (xy 0.2 0.055)
            (xy 0.02 -0.125)
            (xy -0.2 -0.125)
          )
          (width 0.01) (fill yes))
      ))
    (pad "3" smd custom (at 0.45 0.325) (size 0.1 0.1) (layers "F.Cu")
      (net 20 "PL_3V3") (pinfunction "EN") (pintype "input") (zone_connect 2)
      (options (clearance outline) (anchor rect))
      (primitives
        (gr_poly
          (pts
            (xy 0.2 0.125)
            (xy -0.2 0.125)
            (xy -0.2 0.055)
            (xy -0.02 -0.125)
            (xy 0.2 -0.125)
          )
          (width 0.01) (fill yes))
      ))
    (pad "4" smd custom (at 0.45 -0.327) (size 0.1 0.1) (layers "F.Cu")
      (net 20 "PL_3V3") (pinfunction "VIN") (pintype "power_in") (zone_connect 2)
      (options (clearance outline) (anchor rect))
      (primitives
        (gr_poly
          (pts
            (xy 0.2 -0.125)
            (xy -0.2 -0.125)
            (xy -0.2 -0.055)
            (xy -0.02 0.125)
            (xy 0.2 0.125)
          )
          (width 0.01) (fill yes))
      ))
    (pad "5" smd rect (at 0 0 45) (size 0.48 0.48) (layers "F.Cu" "F.Mask")
      (net 1 "GND") (pinfunction "EP") (pintype "passive") (zone_connect 2))
  )
	(footprint "kria-k26-devboard-footprints:C_0402_1005Metric" (layer "F.Cu")
    (at 82.28 117.84 -90)
    (descr "Capacitor SMD 0402")
    (tags "capacitor SMD 0402")
    (property "Author" "Antmicro")
    (property "DNP" "DNP")
    (property "Dielectric" "")
    (property "License" "Apache-2.0")
    (property "MPN" "C1005X5R1E474M050BB")
    (property "Manufacturer" "TDK")
    (property "Sheetfile" "camera.kicad_sch")
    (property "Sheetname" "Camera interface")
    (property "Val" "470n")
    (property "Voltage" "")
    (property "dnp" "")
    (property "exclude_from_bom" "")
    (property "ki_description" " ")
    (attr exclude_from_pos_files exclude_from_bom)
    (fp_text reference "C31" (at -0.86 -0.4 -90) (layer "F.SilkS")
        (effects (font (size 0.7 0.7) (thickness 0.15)) (justify left bottom))
    )
    (fp_text value "C_470n_0402" (at 0 1.4 -90) (layer "F.Fab") hide
        (effects (font (size 0.7 0.7) (thickness 0.15)) (justify left bottom))
    )
    (fp_text user "License: Apache-2.0" (at -0.932 5.17 -90) (layer "F.Fab") hide
        (effects (font (size 0.7 0.7) (thickness 0.15)) (justify left bottom))
    )
    (fp_text user "${REFERENCE}" (at -0.932 3.168 -90) (layer "F.Fab") hide
        (effects (font (size 0.7 0.7) (thickness 0.15)) (justify left bottom))
    )
    (fp_text user "Author: Antmicro" (at -0.932 4.17 -90) (layer "F.Fab") hide
        (effects (font (size 0.7 0.7) (thickness 0.15)) (justify left bottom))
    )
    (fp_rect (start -0.94 -0.47) (end 0.94 0.47)
      (stroke (width 0.05) (type solid)) (fill none) (layer "F.CrtYd"))
    (fp_rect (start -0.499 -0.249) (end 0.499 0.249)
      (stroke (width 0.15) (type solid)) (fill none) (layer "F.Fab"))
    (pad "1" smd roundrect (at -0.484 0 270) (size 0.59 0.64) (layers "F.Cu" "F.Paste" "F.Mask") (roundrect_rratio 0.25)
      (net 322 "PL_1V8") (pintype "passive"))
    (pad "2" smd roundrect (at 0.484 0 270) (size 0.59 0.64) (layers "F.Cu" "F.Paste" "F.Mask") (roundrect_rratio 0.25)
      (net 1 "GND") (pintype "passive"))
  )
	(footprint "kria-k26-devboard-footprints:C_0402_1005Metric" (layer "F.Cu")
    (at 83.874999 119.35 180)
    (descr "Capacitor SMD 0402")
    (tags "capacitor SMD 0402")
    (property "Author" "Antmicro")
    (property "DNP" "DNP")
    (property "Dielectric" "")
    (property "License" "Apache-2.0")
    (property "MPN" "C1005X5R1E474M050BB")
    (property "Manufacturer" "TDK")
    (property "Sheetfile" "camera.kicad_sch")
    (property "Sheetname" "Camera interface")
    (property "Val" "470n")
    (property "Voltage" "")
    (property "dnp" "")
    (property "exclude_from_bom" "")
    (property "ki_description" " ")
    (attr exclude_from_pos_files exclude_from_bom)
    (fp_text reference "C30" (at 1.044999 3.13 180) (layer "F.SilkS")
        (effects (font (size 0.7 0.7) (thickness 0.15)) (justify left bottom))
    )
    (fp_text value "C_470n_0402" (at 0 1.4 180) (layer "F.Fab") hide
        (effects (font (size 0.7 0.7) (thickness 0.15)) (justify left bottom))
    )
    (fp_text user "Author: Antmicro" (at -0.932 4.17 180) (layer "F.Fab") hide
        (effects (font (size 0.7 0.7) (thickness 0.15)) (justify left bottom))
    )
    (fp_text user "${REFERENCE}" (at -0.932 3.168 180) (layer "F.Fab") hide
        (effects (font (size 0.7 0.7) (thickness 0.15)) (justify left bottom))
    )
    (fp_text user "License: Apache-2.0" (at -0.932 5.17 180) (layer "F.Fab") hide
        (effects (font (size 0.7 0.7) (thickness 0.15)) (justify left bottom))
    )
    (fp_rect (start -0.94 -0.47) (end 0.94 0.47)
      (stroke (width 0.05) (type solid)) (fill none) (layer "F.CrtYd"))
    (fp_rect (start -0.499 -0.249) (end 0.499 0.249)
      (stroke (width 0.15) (type solid)) (fill none) (layer "F.Fab"))
    (pad "1" smd roundrect (at -0.484 0 180) (size 0.59 0.64) (layers "F.Cu" "F.Paste" "F.Mask") (roundrect_rratio 0.25)
      (net 20 "PL_3V3") (pintype "passive"))
    (pad "2" smd roundrect (at 0.484 0 180) (size 0.59 0.64) (layers "F.Cu" "F.Paste" "F.Mask") (roundrect_rratio 0.25)
      (net 1 "GND") (pintype "passive"))
  )
	(footprint "kria-k26-devboard-footprints:TP_SMD_0.75mm" (layer "F.Cu")
    (at 134.725 117.825)
    (property "Author" "Antmicro")
    (property "License" "Apache-2.0")
    (property "MPN" "")
    (property "Manufacturer" "")
    (property "Sheetfile" "pcie-m2-key-e.kicad_sch")
    (property "Sheetname" "PCIE M2 key E ")
    (property "ki_description" "Test Point 0.75mm")
    (attr exclude_from_pos_files)
    (fp_text reference "TP47" (at -1.345 1.225) (layer "F.SilkS")
        (effects (font (size 0.7 0.7) (thickness 0.15)) (justify left bottom))
    )
    (fp_text value "TP_0.75mm_SMD" (at 0 1.2) (layer "F.Fab") hide
        (effects (font (size 0.7 0.7) (thickness 0.15)) (justify left bottom))
    )
    (fp_text user "License: Apache-2.0" (at -0.4 5.101) (layer "F.Fab") hide
        (effects (font (size 0.7 0.7) (thickness 0.15)) (justify left bottom))
    )
    (fp_text user "${REFERENCE}" (at -0.4 2.7) (layer "F.Fab") hide
        (effects (font (size 0.7 0.7) (thickness 0.15)) (justify left bottom))
    )
    (fp_text user "Author: Antmicro" (at -0.4 3.901) (layer "F.Fab") hide
        (effects (font (size 0.7 0.7) (thickness 0.15)) (justify left bottom))
    )
    (pad "1" smd circle (at 0 0) (size 0.75 0.75) (layers "F.Cu" "F.Mask")
      (net 396 "Net-(J12-~{CLKREQ0})") (pinfunction "1") (pintype "passive"))
  )
)
